(kicad_pcb
	(version 20260206)
	(generator "pcbnew")
	(generator_version "10.0")
	(general
		(thickness 1.6)
		(legacy_teardrops no)
	)
	(paper "A4")
	(title_block
		(title "Bryce Canyon_IOM_M2_16342-2_OCP.brd")
		(comment 1 "Bryce Canyon / footprints 241-241 of 1146")
	)
	(layers
		(0 "F.Cu" signal "TOP")
		(4 "In1.Cu" signal "L2GND")
		(6 "In2.Cu" signal "L3")
		(8 "In3.Cu" signal "L4VCC")
		(10 "In4.Cu" signal "L5VCC")
		(12 "In5.Cu" signal "L6")
		(14 "In6.Cu" signal "L7GND")
		(2 "B.Cu" signal "BOTTOM")
		(9 "F.Adhes" user "F.Adhesive")
		(11 "B.Adhes" user "B.Adhesive")
		(13 "F.Paste" user "Package Geometry/Pastemask Top")
		(15 "B.Paste" user "Package Geometry/Pastemask Bottom")
		(5 "F.SilkS" user "Ref Des/Silkscreen Top")
		(7 "B.SilkS" user "Ref Des/Silkscreen Bottom")
		(1 "F.Mask" user "Board Geometry/Soldermask Top")
		(3 "B.Mask" user "Board Geometry/Soldermask Bottom")
		(17 "Dwgs.User" user "User.Drawings")
		(19 "Cmts.User" user "User.Comments")
		(21 "Eco1.User" user "User.Eco1")
		(23 "Eco2.User" user "User.Eco2")
		(25 "Edge.Cuts" user "Board Geometry/Outline")
		(27 "Margin" user)
		(31 "F.CrtYd" user "Package Geometry/Place Bound Top")
		(29 "B.CrtYd" user "Package Geometry/Place Bound Bottom")
		(35 "F.Fab" user "Ref Des/Assembly Top")
		(33 "B.Fab" user "Ref Des/Assembly Bottom")
	)
	(footprint ""
		(layer "F.Cu")
		(at 59.944 -162.7886)
		(property "Reference" "R407"
			(at 0 0 0)
			(layer "F.SilkS")
			(hide yes)
			(effects
				(font
					(size 1.27 1.27)
				)
			)
		)
		(property "Value" "1K4R2F-1-GP"
			(at 0.064008 -3.993896 0)
			(unlocked yes)
			(layer "F.Fab")
			(hide yes)
			(effects
				(font
					(size 1.016 1.016)
					(thickness 0.1524)
				)
			)
		)
		(property "Device Type" "R402H16"
			(at 0.064008 -5.517896 0)
			(unlocked yes)
			(layer "F.Fab")
			(hide yes)
			(effects
				(font
					(size 1.016 1.016)
					(thickness 0.1524)
				)
			)
		)
		(duplicate_pad_numbers_are_jumpers no)
		(fp_line
			(start -0.508 -0.9398)
			(end -0.508 0.9398)
			(stroke
				(width 0.1524)
				(type default)
			)
			(layer "F.SilkS")
		)
		(fp_line
			(start 0.508 -0.9398)
			(end -0.508 -0.9398)
			(stroke
				(width 0.1524)
				(type default)
			)
			(layer "F.SilkS")
		)
		(fp_rect
			(start -0.508 0.9398)
			(end 0.508 -0.9398)
			(stroke
				(width 0)
				(type default)
			)
			(fill no)
			(layer "F.CrtYd")
		)
		(fp_rect
			(start -0.508 0.9398)
			(end 0.508 -0.9398)
			(stroke
				(width 0)
				(type default)
			)
			(fill no)
			(layer "F.Fab")
		)
		(pad "1" smd custom
			(at 0 -0.4445)
			(size 0.1397 0.1397)
			(layers "F.Cu" "F.Mask" "F.Paste")
			(net "P3V3_STBY")
			(options
				(clearance outline)
				(anchor circle)
			)
			(primitives
				(gr_poly
					(pts
						(arc
							(start -0.1778 -0.2794)
							(mid -0.249642 -0.249642)
							(end -0.2794 -0.1778)
						)
						(arc
							(start -0.2794 0.1778)
							(mid -0.249642 0.249642)
							(end -0.1778 0.2794)
						)
						(arc
							(start 0.1778 0.2794)
							(mid 0.249642 0.249642)
							(end 0.2794 0.1778)
						)
						(arc
							(start 0.2794 -0.1778)
							(mid 0.249642 -0.249642)
							(end 0.1778 -0.2794)
						)
					)
					(width 0)
					(fill yes)
				)
			)
		)
		(pad "2" smd custom
			(at 0 0.4445)
			(size 0.1397 0.1397)
			(layers "F.Cu" "F.Mask" "F.Paste")
			(net "ADC_P3V3_STBY")
			(options
				(clearance outline)
				(anchor circle)
			)
			(primitives
				(gr_poly
					(pts
						(arc
							(start -0.1778 -0.2794)
							(mid -0.249642 -0.249642)
							(end -0.2794 -0.1778)
						)
						(arc
							(start -0.2794 0.1778)
							(mid -0.249642 0.249642)
							(end -0.1778 0.2794)
						)
						(arc
							(start 0.1778 0.2794)
							(mid 0.249642 0.249642)
							(end 0.2794 0.1778)
						)
						(arc
							(start 0.2794 -0.1778)
							(mid 0.249642 -0.249642)
							(end 0.1778 -0.2794)
						)
					)
					(width 0)
					(fill yes)
				)
			)
		)
	)
)
